# BASEBOARD_FAB2 (Tioga Pass) — schematic netlist excerpt (pin names and nets, part order shuffled) for the footprints in the layout excerpt that follows; sources: Cadence DE-HDL packaged netlist, KiCad conversion of Wiwynn_Tioga_Pass_MB.brd

C4P1  CAP  47UF 4V 20% X6S  pkg 0805  page 42 : A = PVCCIO_CPU0 ; B = GND
C1L19  CAP  1.0UF 16V 10% X6S  pkg 0402  page 112 : A = P3V3_STBY ; B = GND
C25W35  CAP  1.0UF 16V 10% X6S  pkg 0402  page 149 : A = VCC_DACAV3V3 ; B = GND

(kicad_pcb
	(version 20260206)
	(generator "pcbnew")
	(generator_version "10.0")
	(general
		(thickness 1.6)
		(legacy_teardrops no)
	)
	(paper "A4")
	(title_block
		(title "Wiwynn_Tioga_Pass_MB.brd")
		(comment 1 "Tioga Pass / footprints 3234-3236 of 4770")
	)
	(layers
		(0 "F.Cu" signal "TOP")
		(4 "In1.Cu" signal "L2GND")
		(6 "In2.Cu" signal "L3")
		(8 "In3.Cu" signal "L4GND")
		(10 "In4.Cu" signal "L5")
		(12 "In5.Cu" signal "L6GND")
		(14 "In6.Cu" signal "L7VCC")
		(16 "In7.Cu" signal "L8VCC")
		(18 "In8.Cu" signal "L9GND")
		(20 "In9.Cu" signal "L10")
		(22 "In10.Cu" signal "L11GND")
		(24 "In11.Cu" signal "L12")
		(26 "In12.Cu" signal "L13GND")
		(2 "B.Cu" signal "BOTTOM")
		(9 "F.Adhes" user "F.Adhesive")
		(11 "B.Adhes" user "B.Adhesive")
		(13 "F.Paste" user "Package Geometry/Pastemask Top")
		(15 "B.Paste" user "Package Geometry/Pastemask Bottom")
		(5 "F.SilkS" user "Ref Des/Silkscreen Top")
		(7 "B.SilkS" user "Ref Des/Silkscreen Bottom")
		(1 "F.Mask" user "Board Geometry/Soldermask Top")
		(3 "B.Mask" user "Board Geometry/Soldermask Bottom")
		(17 "Dwgs.User" user "User.Drawings")
		(19 "Cmts.User" user "User.Comments")
		(21 "Eco1.User" user "User.Eco1")
		(23 "Eco2.User" user "User.Eco2")
		(25 "Edge.Cuts" user "Board Geometry/Outline")
		(27 "Margin" user)
		(31 "F.CrtYd" user "Package Geometry/Place Bound Top")
		(29 "B.CrtYd" user "Package Geometry/Place Bound Bottom")
		(35 "F.Fab" user "Ref Des/Assembly Top")
		(33 "B.Fab" user "Ref Des/Assembly Bottom")
	)
	(footprint ""
		(layer "B.Cu")
		(at 403.391624 -32.801052)
		(property "Reference" "C25W35"
			(at 0.8382 -0.67818 0)
			(unlocked yes)
			(layer "B.SilkS")
			(effects
				(font
					(size 0.4064 0.254)
					(thickness 0.1524)
				)
				(justify left mirror)
			)
		)
		(property "Value" ""
			(at 0 0 0)
			(layer "B.Fab")
			(effects
				(font
					(size 1.27 1.27)
				)
				(justify mirror)
			)
		)
		(duplicate_pad_numbers_are_jumpers no)
		(fp_poly
			(pts
				(xy -0.3048 -0.1016) (xy -0.3048 0.9906) (xy 0.3048 0.9906) (xy 0.3048 -0.1016)
			)
			(stroke
				(width 0)
				(type default)
			)
			(fill no)
			(layer "B.CrtYd")
		)
		(fp_line
			(start -0.3048 -0.1016)
			(end 0.3048 -0.1016)
			(stroke
				(width 0.1)
				(type default)
			)
			(layer "B.Fab")
		)
		(fp_line
			(start -0.3048 0.9906)
			(end -0.3048 -0.1016)
			(stroke
				(width 0.1)
				(type default)
			)
			(layer "B.Fab")
		)
		(fp_line
			(start 0.3048 -0.1016)
			(end 0.3048 0.9906)
			(stroke
				(width 0.1)
				(type default)
			)
			(layer "B.Fab")
		)
		(fp_line
			(start 0.3048 0.9906)
			(end -0.3048 0.9906)
			(stroke
				(width 0.1)
				(type default)
			)
			(layer "B.Fab")
		)
		(pad "1" smd rect
			(at 0 0 180)
			(size 0.508 0.508)
			(layers "B.Cu" "B.Mask" "B.Paste")
			(net "VCC_DACAV3V3")
		)
		(pad "2" smd rect
			(at 0 0.889 180)
			(size 0.508 0.508)
			(layers "B.Cu" "B.Mask" "B.Paste")
			(net "GND")
		)
		(zone
			(layer "B.Cu")
			(hatch none 0.5)
			(connect_pads
				(clearance 0)
			)
			(min_thickness 0.25)
			(keepout
				(tracks allowed)
				(vias not_allowed)
				(pads allowed)
				(copperpour not_allowed)
				(footprints allowed)
			)
			(placement
				(enabled no)
				(sheetname "")
			)
			(fill
				(thermal_gap 0.5)
				(thermal_bridge_width 0.5)
				(island_removal_mode 0)
			)
			(polygon
				(pts
					(xy 403.645624 -32.547052) (xy 403.137624 -32.547052) (xy 403.137624 -32.166052) (xy 403.645624 -32.166052)
				)
			)
		)
		(zone
			(layer "B.Cu")
			(hatch none 0.5)
			(connect_pads
				(clearance 0)
			)
			(min_thickness 0.25)
			(keepout
				(tracks not_allowed)
				(vias allowed)
				(pads allowed)
				(copperpour not_allowed)
				(footprints allowed)
			)
			(placement
				(enabled no)
				(sheetname "")
			)
			(fill
				(thermal_gap 0.5)
				(thermal_bridge_width 0.5)
				(island_removal_mode 0)
			)
			(polygon
				(pts
					(xy 403.645624 -32.166052) (xy 403.137624 -32.166052) (xy 403.137624 -32.547052) (xy 403.645624 -32.547052)
				)
			)
		)
	)
	(footprint ""
		(layer "B.Cu")
		(at 280.735024 -80.096614 180)
		(property "Reference" "C4P1"
			(at 0 0 0)
			(layer "B.SilkS")
			(hide yes)
			(effects
				(font
					(size 1.27 1.27)
				)
				(justify mirror)
			)
		)
		(property "Value" ""
			(at 0 0 0)
			(layer "B.Fab")
			(effects
				(font
					(size 1.27 1.27)
				)
				(justify mirror)
			)
		)
		(duplicate_pad_numbers_are_jumpers no)
		(fp_poly
			(pts
				(xy 0.7239 -0.2159) (xy -0.7239 -0.2159) (xy -0.7239 1.9939) (xy 0.7239 1.9939)
			)
			(stroke
				(width 0)
				(type default)
			)
			(fill no)
			(layer "B.CrtYd")
		)
		(fp_line
			(start 0.7239 1.9939)
			(end -0.7239 1.9939)
			(stroke
				(width 0.1)
				(type default)
			)
			(layer "B.Fab")
		)
		(fp_line
			(start 0.7239 -0.2159)
			(end 0.7239 1.9939)
			(stroke
				(width 0.1)
				(type default)
			)
			(layer "B.Fab")
		)
		(fp_line
			(start -0.7239 1.9939)
			(end -0.7239 -0.2159)
			(stroke
				(width 0.1)
				(type default)
			)
			(layer "B.Fab")
		)
		(fp_line
			(start -0.7239 -0.2159)
			(end 0.7239 -0.2159)
			(stroke
				(width 0.1)
				(type default)
			)
			(layer "B.Fab")
		)
		(pad "1" smd rect
			(at 0 0)
			(size 1.27 1.016)
			(layers "B.Cu" "B.Mask" "B.Paste")
			(net "PVCCIO_CPU0")
		)
		(pad "2" smd rect
			(at 0 1.778)
			(size 1.27 1.016)
			(layers "B.Cu" "B.Mask" "B.Paste")
			(net "GND")
		)
		(zone
			(layer "B.Cu")
			(hatch none 0.5)
			(connect_pads
				(clearance 0)
			)
			(min_thickness 0.25)
			(keepout
				(tracks not_allowed)
				(vias allowed)
				(pads allowed)
				(copperpour not_allowed)
				(footprints allowed)
			)
			(placement
				(enabled no)
				(sheetname "")
			)
			(fill
				(thermal_gap 0.5)
				(thermal_bridge_width 0.5)
				(island_removal_mode 0)
			)
			(polygon
				(pts
					(xy 280.100024 -80.604614) (xy 281.370024 -80.604614) (xy 281.370024 -81.366614) (xy 280.100024 -81.366614)
				)
			)
		)
	)
	(footprint ""
		(layer "B.Cu")
		(at 456.7555 -135.0772 180)
		(property "Reference" "C1L19"
			(at 0 0 0)
			(layer "B.SilkS")
			(hide yes)
			(effects
				(font
					(size 1.27 1.27)
				)
				(justify mirror)
			)
		)
		(property "Value" ""
			(at 0 0 0)
			(layer "B.Fab")
			(effects
				(font
					(size 1.27 1.27)
				)
				(justify mirror)
			)
		)
		(duplicate_pad_numbers_are_jumpers no)
		(fp_poly
			(pts
				(xy -0.3048 -0.1016) (xy -0.3048 0.9906) (xy 0.3048 0.9906) (xy 0.3048 -0.1016)
			)
			(stroke
				(width 0)
				(type default)
			)
			(fill no)
			(layer "B.CrtYd")
		)
		(fp_line
			(start 0.3048 0.9906)
			(end -0.3048 0.9906)
			(stroke
				(width 0.1)
				(type default)
			)
			(layer "B.Fab")
		)
		(fp_line
			(start 0.3048 -0.1016)
			(end 0.3048 0.9906)
			(stroke
				(width 0.1)
				(type default)
			)
			(layer "B.Fab")
		)
		(fp_line
			(start -0.3048 0.9906)
			(end -0.3048 -0.1016)
			(stroke
				(width 0.1)
				(type default)
			)
			(layer "B.Fab")
		)
		(fp_line
			(start -0.3048 -0.1016)
			(end 0.3048 -0.1016)
			(stroke
				(width 0.1)
				(type default)
			)
			(layer "B.Fab")
		)
		(pad "1" smd rect
			(at 0 0)
			(size 0.508 0.508)
			(layers "B.Cu" "B.Mask" "B.Paste")
			(net "P3V3_STBY")
		)
		(pad "2" smd rect
			(at 0 0.889)
			(size 0.508 0.508)
			(layers "B.Cu" "B.Mask" "B.Paste")
			(net "GND")
		)
		(zone
			(layer "B.Cu")
			(hatch none 0.5)
			(connect_pads
				(clearance 0)
			)
			(min_thickness 0.25)
			(keepout
				(tracks not_allowed)
				(vias allowed)
				(pads allowed)
				(copperpour not_allowed)
				(footprints allowed)
			)
			(placement
				(enabled no)
				(sheetname "")
			)
			(fill
				(thermal_gap 0.5)
				(thermal_bridge_width 0.5)
				(island_removal_mode 0)
			)
			(polygon
				(pts
					(xy 456.5015 -135.7122) (xy 457.0095 -135.7122) (xy 457.0095 -135.3312) (xy 456.5015 -135.3312)
				)
			)
		)
		(zone
			(layer "B.Cu")
			(hatch none 0.5)
			(connect_pads
				(clearance 0)
			)
			(min_thickness 0.25)
			(keepout
				(tracks allowed)
				(vias not_allowed)
				(pads allowed)
				(copperpour not_allowed)
				(footprints allowed)
			)
			(placement
				(enabled no)
				(sheetname "")
			)
			(fill
				(thermal_gap 0.5)
				(thermal_bridge_width 0.5)
				(island_removal_mode 0)
			)
			(polygon
				(pts
					(xy 456.5015 -135.3312) (xy 457.0095 -135.3312) (xy 457.0095 -135.7122) (xy 456.5015 -135.7122)
				)
			)
		)
	)
)
